FILE_TYPE = CONNECTIVITY;
{Allegro Design Entry HDL 17.4-2019 S026 (4007227) 1/17/2022}
"PAGE_NUMBER" = 403;
0"NC";
END.
